(kicad_pcb
	(version 20260206)
	(generator "pcbnew")
	(generator_version "10.0")
	(general
		(thickness 1.6)
		(legacy_teardrops no)
	)
	(paper "A4")
	(title_block
		(title "01162023_DA0F0TEBIF0_F0T_Expander_BD_F_brd_V02_OCP.brd")
		(comment 1 "Grand Teton / footprints 1230-1237 of 9728")
	)
	(layers
		(0 "F.Cu" signal "TOP")
		(4 "In1.Cu" signal "GND")
		(6 "In2.Cu" signal "VCC")
		(8 "In3.Cu" signal "VCC1")
		(10 "In4.Cu" signal "GND1")
		(12 "In5.Cu" signal "IN1")
		(14 "In6.Cu" signal "GND2")
		(16 "In7.Cu" signal "IN2")
		(18 "In8.Cu" signal "GND3")
		(20 "In9.Cu" signal "IN3")
		(22 "In10.Cu" signal "GND4")
		(24 "In11.Cu" signal "IN4")
		(26 "In12.Cu" signal "GND5")
		(28 "In13.Cu" signal "IN5")
		(30 "In14.Cu" signal "GND6")
		(32 "In15.Cu" signal "IN6")
		(34 "In16.Cu" signal "GND7")
		(2 "B.Cu" signal "BOTTOM")
		(9 "F.Adhes" user "F.Adhesive")
		(11 "B.Adhes" user "B.Adhesive")
		(13 "F.Paste" user "Package Geometry/Pastemask Top")
		(15 "B.Paste" user "Package Geometry/Pastemask Bottom")
		(5 "F.SilkS" user "Ref Des/Silkscreen Top")
		(7 "B.SilkS" user "Ref Des/Silkscreen Bottom")
		(1 "F.Mask" user "Board Geometry/Soldermask Top")
		(3 "B.Mask" user "Board Geometry/Soldermask Bottom")
		(17 "Dwgs.User" user "User.Drawings")
		(19 "Cmts.User" user "User.Comments")
		(21 "Eco1.User" user "User.Eco1")
		(23 "Eco2.User" user "User.Eco2")
		(25 "Edge.Cuts" user "Board Geometry/Outline")
		(27 "Margin" user)
		(31 "F.CrtYd" user "Package Geometry/Place Bound Top")
		(29 "B.CrtYd" user "Package Geometry/Place Bound Bottom")
		(35 "F.Fab" user "Ref Des/Assembly Top")
		(33 "B.Fab" user "Ref Des/Assembly Bottom")
	)
	(footprint ""
		(layer "F.Cu")
		(at 160.720024 -15.649956 180)
		(property "Reference" "H109"
			(at -1.27762 2.488184 0)
			(unlocked yes)
			(layer "B.SilkS")
			(effects
				(font
					(size 0.7874 0.5842)
					(thickness 0.1524)
				)
				(justify left mirror)
			)
		)
		(property "Value" ""
			(at 0 0 180)
			(layer "F.Fab")
			(effects
				(font
					(size 1.27 1.27)
				)
			)
		)
		(duplicate_pad_numbers_are_jumpers no)
		(pad "1" thru_hole rect
			(at 0 0 180)
			(size 4.2164 5.0038)
			(drill 2.0066
				(offset 0.099822 0)
			)
			(layers "*.Cu" "*.Mask")
			(remove_unused_layers no)
			(net "Net_8554")
			(clearance -0.8509)
			(padstack
				(mode front_inner_back)
				(layer "Inner"
					(shape circle)
					(size 4.0132 4.0132)
					(clearance -0.7493)
				)
				(layer "B.Cu"
					(shape circle)
					(size 4.0132 4.0132)
					(clearance -0.7493)
				)
			)
		)
	)
	(footprint ""
		(layer "F.Cu")
		(at 221.990158 -81.627472)
		(property "Reference" "R5766"
			(at 0 0 0)
			(layer "F.SilkS")
			(hide yes)
			(effects
				(font
					(size 1.27 1.27)
				)
			)
		)
		(property "Value" ""
			(at 0 0 0)
			(layer "F.Fab")
			(effects
				(font
					(size 1.27 1.27)
				)
			)
		)
		(duplicate_pad_numbers_are_jumpers no)
		(fp_line
			(start -0.7874 -0.4064)
			(end 0.7874 -0.4064)
			(stroke
				(width 0.1524)
				(type default)
			)
			(layer "F.SilkS")
		)
		(fp_line
			(start -0.7874 0.4064)
			(end -0.7874 -0.4064)
			(stroke
				(width 0.1524)
				(type default)
			)
			(layer "F.SilkS")
		)
		(fp_line
			(start 0.7874 -0.4064)
			(end 0.7874 0.4064)
			(stroke
				(width 0.1524)
				(type default)
			)
			(layer "F.SilkS")
		)
		(fp_line
			(start 0.7874 0.4064)
			(end -0.7874 0.4064)
			(stroke
				(width 0.1524)
				(type default)
			)
			(layer "F.SilkS")
		)
		(fp_line
			(start -0.67945 -0.305054)
			(end -0.12065 -0.305054)
			(stroke
				(width 0.1)
				(type default)
			)
			(layer "F.Fab")
		)
		(fp_line
			(start -0.67945 0.3048)
			(end -0.67945 -0.305054)
			(stroke
				(width 0.1)
				(type default)
			)
			(layer "F.Fab")
		)
		(fp_line
			(start -0.12065 -0.305054)
			(end -0.12065 -0.2794)
			(stroke
				(width 0.1)
				(type default)
			)
			(layer "F.Fab")
		)
		(fp_line
			(start -0.12065 -0.2794)
			(end 0.12065 -0.2794)
			(stroke
				(width 0.1)
				(type default)
			)
			(layer "F.Fab")
		)
		(fp_line
			(start -0.12065 0.2794)
			(end -0.12065 0.3048)
			(stroke
				(width 0.1)
				(type default)
			)
			(layer "F.Fab")
		)
		(fp_line
			(start -0.12065 0.3048)
			(end -0.67945 0.3048)
			(stroke
				(width 0.1)
				(type default)
			)
			(layer "F.Fab")
		)
		(fp_line
			(start 0.120396 0.2794)
			(end -0.12065 0.2794)
			(stroke
				(width 0.1)
				(type default)
			)
			(layer "F.Fab")
		)
		(fp_line
			(start 0.120396 0.3048)
			(end 0.120396 0.2794)
			(stroke
				(width 0.1)
				(type default)
			)
			(layer "F.Fab")
		)
		(fp_line
			(start 0.12065 -0.3048)
			(end 0.67945 -0.3048)
			(stroke
				(width 0.1)
				(type default)
			)
			(layer "F.Fab")
		)
		(fp_line
			(start 0.12065 -0.2794)
			(end 0.12065 -0.3048)
			(stroke
				(width 0.1)
				(type default)
			)
			(layer "F.Fab")
		)
		(fp_line
			(start 0.67945 -0.3048)
			(end 0.67945 0.3048)
			(stroke
				(width 0.1)
				(type default)
			)
			(layer "F.Fab")
		)
		(fp_line
			(start 0.67945 0.3048)
			(end 0.120396 0.3048)
			(stroke
				(width 0.1)
				(type default)
			)
			(layer "F.Fab")
		)
		(pad "1" smd circle
			(at -0.40005 0)
			(size 0 0)
			(layers "F.Cu" "F.Mask" "F.Paste")
			(net "SSD12_LED")
		)
		(pad "2" smd circle
			(at 0.40005 0)
			(size 0 0)
			(layers "F.Cu" "F.Mask" "F.Paste")
			(net "SSD12_LED_R")
		)
	)
	(footprint ""
		(layer "F.Cu")
		(at 228.578664 -207.02016 -90)
		(property "Reference" "R5293"
			(at 0 0 270)
			(layer "F.SilkS")
			(hide yes)
			(effects
				(font
					(size 1.27 1.27)
				)
			)
		)
		(property "Value" ""
			(at 0 0 270)
			(layer "F.Fab")
			(effects
				(font
					(size 1.27 1.27)
				)
			)
		)
		(duplicate_pad_numbers_are_jumpers no)
		(fp_line
			(start -0.7874 0.4064)
			(end -0.7874 -0.4064)
			(stroke
				(width 0.1524)
				(type default)
			)
			(layer "F.SilkS")
		)
		(fp_line
			(start 0.7874 0.4064)
			(end -0.7874 0.4064)
			(stroke
				(width 0.1524)
				(type default)
			)
			(layer "F.SilkS")
		)
		(fp_line
			(start -0.7874 -0.4064)
			(end 0.7874 -0.4064)
			(stroke
				(width 0.1524)
				(type default)
			)
			(layer "F.SilkS")
		)
		(fp_line
			(start 0.7874 -0.4064)
			(end 0.7874 0.4064)
			(stroke
				(width 0.1524)
				(type default)
			)
			(layer "F.SilkS")
		)
		(fp_line
			(start -0.67945 0.3048)
			(end -0.67945 -0.305054)
			(stroke
				(width 0.1)
				(type default)
			)
			(layer "F.Fab")
		)
		(fp_line
			(start -0.12065 0.3048)
			(end -0.67945 0.3048)
			(stroke
				(width 0.1)
				(type default)
			)
			(layer "F.Fab")
		)
		(fp_line
			(start 0.120396 0.3048)
			(end 0.120396 0.2794)
			(stroke
				(width 0.1)
				(type default)
			)
			(layer "F.Fab")
		)
		(fp_line
			(start 0.67945 0.3048)
			(end 0.120396 0.3048)
			(stroke
				(width 0.1)
				(type default)
			)
			(layer "F.Fab")
		)
		(fp_line
			(start -0.12065 0.2794)
			(end -0.12065 0.3048)
			(stroke
				(width 0.1)
				(type default)
			)
			(layer "F.Fab")
		)
		(fp_line
			(start 0.120396 0.2794)
			(end -0.12065 0.2794)
			(stroke
				(width 0.1)
				(type default)
			)
			(layer "F.Fab")
		)
		(fp_line
			(start -0.12065 -0.2794)
			(end 0.12065 -0.2794)
			(stroke
				(width 0.1)
				(type default)
			)
			(layer "F.Fab")
		)
		(fp_line
			(start 0.12065 -0.2794)
			(end 0.12065 -0.3048)
			(stroke
				(width 0.1)
				(type default)
			)
			(layer "F.Fab")
		)
		(fp_line
			(start 0.12065 -0.3048)
			(end 0.67945 -0.3048)
			(stroke
				(width 0.1)
				(type default)
			)
			(layer "F.Fab")
		)
		(fp_line
			(start 0.67945 -0.3048)
			(end 0.67945 0.3048)
			(stroke
				(width 0.1)
				(type default)
			)
			(layer "F.Fab")
		)
		(fp_line
			(start -0.67945 -0.305054)
			(end -0.12065 -0.305054)
			(stroke
				(width 0.1)
				(type default)
			)
			(layer "F.Fab")
		)
		(fp_line
			(start -0.12065 -0.305054)
			(end -0.12065 -0.2794)
			(stroke
				(width 0.1)
				(type default)
			)
			(layer "F.Fab")
		)
		(pad "1" smd circle
			(at -0.40005 0 270)
			(size 0 0)
			(layers "F.Cu" "F.Mask" "F.Paste")
			(net "BIC_SEL_FLASH_SW0")
		)
		(pad "2" smd circle
			(at 0.40005 0 270)
			(size 0 0)
			(layers "F.Cu" "F.Mask" "F.Paste")
			(net "BIC_SEL_FLASH_SW0_R")
		)
	)
	(footprint ""
		(layer "F.Cu")
		(at 268.838426 -123.71324)
		(property "Reference" "C466"
			(at 0 0 0)
			(layer "F.SilkS")
			(hide yes)
			(effects
				(font
					(size 1.27 1.27)
				)
			)
		)
		(property "Value" ""
			(at 0 0 0)
			(layer "F.Fab")
			(effects
				(font
					(size 1.27 1.27)
				)
			)
		)
		(duplicate_pad_numbers_are_jumpers no)
		(fp_line
			(start -0.299974 -0.150114)
			(end 0.299974 -0.150114)
			(stroke
				(width 0.1)
				(type default)
			)
			(layer "F.Fab")
		)
		(fp_line
			(start -0.299974 0.150114)
			(end -0.299974 -0.150114)
			(stroke
				(width 0.1)
				(type default)
			)
			(layer "F.Fab")
		)
		(fp_line
			(start 0.299974 -0.150114)
			(end 0.299974 0.150114)
			(stroke
				(width 0.1)
				(type default)
			)
			(layer "F.Fab")
		)
		(fp_line
			(start 0.299974 0.150114)
			(end -0.299974 0.150114)
			(stroke
				(width 0.1)
				(type default)
			)
			(layer "F.Fab")
		)
		(pad "1" smd rect
			(at -0.2667 0)
			(size 0.3048 0.381)
			(layers "F.Cu" "F.Mask" "F.Paste")
			(net "P5E_PEX2_STN1_TX_DN<26>")
		)
		(pad "2" smd rect
			(at 0.2667 0)
			(size 0.3048 0.381)
			(layers "F.Cu" "F.Mask" "F.Paste")
			(net "P5E_PEX2_STN1_TX_C_DN<26>")
		)
	)
	(footprint ""
		(layer "F.Cu")
		(at 323.884036 -227.494084 180)
		(property "Reference" "D21"
			(at 5.431536 1.316482 0)
			(unlocked yes)
			(layer "F.SilkS")
			(effects
				(font
					(size 0.7874 0.5842)
					(thickness 0.1524)
				)
			)
		)
		(property "Value" ""
			(at 0 0 180)
			(layer "F.Fab")
			(effects
				(font
					(size 1.27 1.27)
				)
			)
		)
		(duplicate_pad_numbers_are_jumpers no)
		(fp_line
			(start 1.16078 0.4826)
			(end -0.64008 0.4826)
			(stroke
				(width 0.1524)
				(type default)
			)
			(layer "F.SilkS")
		)
		(fp_line
			(start 1.16078 -0.4826)
			(end 1.16078 0.4826)
			(stroke
				(width 0.1524)
				(type default)
			)
			(layer "F.SilkS")
		)
		(fp_line
			(start 1.03378 0.4826)
			(end -0.79248 0.4826)
			(stroke
				(width 0.1524)
				(type default)
			)
			(layer "F.SilkS")
		)
		(fp_line
			(start 1.03378 -0.4826)
			(end 1.03378 0.4826)
			(stroke
				(width 0.1524)
				(type default)
			)
			(layer "F.SilkS")
		)
		(fp_line
			(start 0.90678 0.4826)
			(end -0.90678 0.4826)
			(stroke
				(width 0.1524)
				(type default)
			)
			(layer "F.SilkS")
		)
		(fp_line
			(start 0.90678 -0.4826)
			(end 0.90678 0.4826)
			(stroke
				(width 0.1524)
				(type default)
			)
			(layer "F.SilkS")
		)
		(fp_line
			(start -0.64008 -0.4826)
			(end 1.16078 -0.4826)
			(stroke
				(width 0.1524)
				(type default)
			)
			(layer "F.SilkS")
		)
		(fp_line
			(start -0.79248 -0.4826)
			(end 1.03378 -0.4826)
			(stroke
				(width 0.1524)
				(type default)
			)
			(layer "F.SilkS")
		)
		(fp_line
			(start -0.89408 -0.4826)
			(end 0.90678 -0.4826)
			(stroke
				(width 0.1524)
				(type default)
			)
			(layer "F.SilkS")
		)
		(fp_line
			(start -0.90678 0.4826)
			(end -0.90678 -0.4699)
			(stroke
				(width 0.1524)
				(type default)
			)
			(layer "F.SilkS")
		)
		(fp_line
			(start 0.499872 0.249936)
			(end -0.499872 0.249936)
			(stroke
				(width 0.1)
				(type default)
			)
			(layer "F.Fab")
		)
		(fp_line
			(start 0.499872 -0.249936)
			(end 0.499872 0.249936)
			(stroke
				(width 0.1)
				(type default)
			)
			(layer "F.Fab")
		)
		(fp_line
			(start -0.499872 0.249936)
			(end -0.499872 -0.249936)
			(stroke
				(width 0.1)
				(type default)
			)
			(layer "F.Fab")
		)
		(fp_line
			(start -0.499872 -0.249936)
			(end 0.499872 -0.249936)
			(stroke
				(width 0.1)
				(type default)
			)
			(layer "F.Fab")
		)
		(pad "A" smd rect
			(at -0.47498 0 180)
			(size 0.6096 0.7112)
			(layers "F.Cu" "F.Mask" "F.Paste")
			(net "FPGA_HEARTBEAT")
		)
		(pad "C" smd rect
			(at 0.47498 0 180)
			(size 0.6096 0.7112)
			(layers "F.Cu" "F.Mask" "F.Paste")
			(net "FPGA_HEARTBEAT_N")
		)
	)
	(footprint ""
		(layer "F.Cu")
		(at 174.596552 -350.098614 90)
		(property "Reference" "C2524"
			(at 0 0 90)
			(layer "F.SilkS")
			(hide yes)
			(effects
				(font
					(size 1.27 1.27)
				)
			)
		)
		(property "Value" ""
			(at 0 0 90)
			(layer "F.Fab")
			(effects
				(font
					(size 1.27 1.27)
				)
			)
		)
		(duplicate_pad_numbers_are_jumpers no)
		(fp_line
			(start 0.299974 -0.150114)
			(end 0.299974 0.150114)
			(stroke
				(width 0.1)
				(type default)
			)
			(layer "F.Fab")
		)
		(fp_line
			(start -0.299974 -0.150114)
			(end 0.299974 -0.150114)
			(stroke
				(width 0.1)
				(type default)
			)
			(layer "F.Fab")
		)
		(fp_line
			(start 0.299974 0.150114)
			(end -0.299974 0.150114)
			(stroke
				(width 0.1)
				(type default)
			)
			(layer "F.Fab")
		)
		(fp_line
			(start -0.299974 0.150114)
			(end -0.299974 -0.150114)
			(stroke
				(width 0.1)
				(type default)
			)
			(layer "F.Fab")
		)
		(pad "1" smd rect
			(at -0.2667 0 90)
			(size 0.3048 0.381)
			(layers "F.Cu" "F.Mask" "F.Paste")
			(net "P5E_PEX1_STN4_TX_DP<73>")
		)
		(pad "2" smd rect
			(at 0.2667 0 90)
			(size 0.3048 0.381)
			(layers "F.Cu" "F.Mask" "F.Paste")
			(net "P5E_PEX1_STN4_TX_C_DP<73>")
		)
	)
	(footprint ""
		(layer "F.Cu")
		(at 321.804284 -350.098614 90)
		(property "Reference" "C559"
			(at 0 0 90)
			(layer "F.SilkS")
			(hide yes)
			(effects
				(font
					(size 1.27 1.27)
				)
			)
		)
		(property "Value" ""
			(at 0 0 90)
			(layer "F.Fab")
			(effects
				(font
					(size 1.27 1.27)
				)
			)
		)
		(duplicate_pad_numbers_are_jumpers no)
		(fp_line
			(start 0.299974 -0.150114)
			(end 0.299974 0.150114)
			(stroke
				(width 0.1)
				(type default)
			)
			(layer "F.Fab")
		)
		(fp_line
			(start -0.299974 -0.150114)
			(end 0.299974 -0.150114)
			(stroke
				(width 0.1)
				(type default)
			)
			(layer "F.Fab")
		)
		(fp_line
			(start 0.299974 0.150114)
			(end -0.299974 0.150114)
			(stroke
				(width 0.1)
				(type default)
			)
			(layer "F.Fab")
		)
		(fp_line
			(start -0.299974 0.150114)
			(end -0.299974 -0.150114)
			(stroke
				(width 0.1)
				(type default)
			)
			(layer "F.Fab")
		)
		(pad "1" smd rect
			(at -0.2667 0 90)
			(size 0.3048 0.381)
			(layers "F.Cu" "F.Mask" "F.Paste")
			(net "P5E_PEX2_STN6_TX_DP<107>")
		)
		(pad "2" smd rect
			(at 0.2667 0 90)
			(size 0.3048 0.381)
			(layers "F.Cu" "F.Mask" "F.Paste")
			(net "P5E_PEX2_STN6_TX_C_DP<107>")
		)
	)
	(footprint ""
		(layer "F.Cu")
		(at 220.34373 -43.85691)
		(property "Reference" "R585"
			(at 0 0 0)
			(layer "F.SilkS")
			(hide yes)
			(effects
				(font
					(size 1.27 1.27)
				)
			)
		)
		(property "Value" ""
			(at 0 0 0)
			(layer "F.Fab")
			(effects
				(font
					(size 1.27 1.27)
				)
			)
		)
		(duplicate_pad_numbers_are_jumpers no)
		(fp_line
			(start -0.7874 -0.4064)
			(end 0.7874 -0.4064)
			(stroke
				(width 0.1524)
				(type default)
			)
			(layer "F.SilkS")
		)
		(fp_line
			(start -0.7874 0.4064)
			(end -0.7874 -0.4064)
			(stroke
				(width 0.1524)
				(type default)
			)
			(layer "F.SilkS")
		)
		(fp_line
			(start 0.7874 -0.4064)
			(end 0.7874 0.4064)
			(stroke
				(width 0.1524)
				(type default)
			)
			(layer "F.SilkS")
		)
		(fp_line
			(start 0.7874 0.4064)
			(end -0.7874 0.4064)
			(stroke
				(width 0.1524)
				(type default)
			)
			(layer "F.SilkS")
		)
		(fp_line
			(start -0.67945 -0.305054)
			(end -0.12065 -0.305054)
			(stroke
				(width 0.1)
				(type default)
			)
			(layer "F.Fab")
		)
		(fp_line
			(start -0.67945 0.3048)
			(end -0.67945 -0.305054)
			(stroke
				(width 0.1)
				(type default)
			)
			(layer "F.Fab")
		)
		(fp_line
			(start -0.12065 -0.305054)
			(end -0.12065 -0.2794)
			(stroke
				(width 0.1)
				(type default)
			)
			(layer "F.Fab")
		)
		(fp_line
			(start -0.12065 -0.2794)
			(end 0.12065 -0.2794)
			(stroke
				(width 0.1)
				(type default)
			)
			(layer "F.Fab")
		)
		(fp_line
			(start -0.12065 0.2794)
			(end -0.12065 0.3048)
			(stroke
				(width 0.1)
				(type default)
			)
			(layer "F.Fab")
		)
		(fp_line
			(start -0.12065 0.3048)
			(end -0.67945 0.3048)
			(stroke
				(width 0.1)
				(type default)
			)
			(layer "F.Fab")
		)
		(fp_line
			(start 0.120396 0.2794)
			(end -0.12065 0.2794)
			(stroke
				(width 0.1)
				(type default)
			)
			(layer "F.Fab")
		)
		(fp_line
			(start 0.120396 0.3048)
			(end 0.120396 0.2794)
			(stroke
				(width 0.1)
				(type default)
			)
			(layer "F.Fab")
		)
		(fp_line
			(start 0.12065 -0.3048)
			(end 0.67945 -0.3048)
			(stroke
				(width 0.1)
				(type default)
			)
			(layer "F.Fab")
		)
		(fp_line
			(start 0.12065 -0.2794)
			(end 0.12065 -0.3048)
			(stroke
				(width 0.1)
				(type default)
			)
			(layer "F.Fab")
		)
		(fp_line
			(start 0.67945 -0.3048)
			(end 0.67945 0.3048)
			(stroke
				(width 0.1)
				(type default)
			)
			(layer "F.Fab")
		)
		(fp_line
			(start 0.67945 0.3048)
			(end 0.120396 0.3048)
			(stroke
				(width 0.1)
				(type default)
			)
			(layer "F.Fab")
		)
		(pad "1" smd circle
			(at -0.40005 0)
			(size 0 0)
			(layers "F.Cu" "F.Mask" "F.Paste")
			(net "SSD7_ADC_A1")
		)
		(pad "2" smd circle
			(at 0.40005 0)
			(size 0 0)
			(layers "F.Cu" "F.Mask" "F.Paste")
			(net "GND")
		)
	)
)
